(kicad_pcb
	(version 20241229)
	(generator "pcbnew")
	(generator_version "9.0")
	(general
		(thickness 1.62)
		(legacy_teardrops no)
	)
	(paper "A3")
	(title_block
		(title "COM Express 7 Baseboard")
		(date "2025-02-04")
		(rev "1.1.2")
		(company "Antmicro Ltd")
		(comment 1 "www.antmicro.com")
		(comment 9 "footprints 453-455 of 802")
	)
	(layers
		(0 "F.Cu" signal)
		(4 "In1.Cu" signal)
		(6 "In2.Cu" signal)
		(8 "In3.Cu" signal)
		(10 "In4.Cu" signal)
		(12 "In5.Cu" signal)
		(14 "In6.Cu" signal)
		(2 "B.Cu" signal)
		(9 "F.Adhes" user "F.Adhesive")
		(11 "B.Adhes" user "B.Adhesive")
		(13 "F.Paste" user)
		(15 "B.Paste" user)
		(5 "F.SilkS" user "F.Silkscreen")
		(7 "B.SilkS" user "B.Silkscreen")
		(1 "F.Mask" user)
		(3 "B.Mask" user)
		(17 "Dwgs.User" user "User.Drawings")
		(19 "Cmts.User" user "User.Comments")
		(21 "Eco1.User" user "User.Eco1")
		(23 "Eco2.User" user "User.Eco2")
		(25 "Edge.Cuts" user)
		(27 "Margin" user)
		(31 "F.CrtYd" user "F.Courtyard")
		(29 "B.CrtYd" user "B.Courtyard")
		(35 "F.Fab" user)
		(33 "B.Fab" user)
	)
	(footprint "antmicro-footprints:QFN-20-1EP_3x3mm_P0.45mm_TPS56xxxx"
		(layer "F.Cu")
		(at 311.714999 120.558999 180)
		(property "Reference" "U18"
			(at -1.835001 1.798999 0)
			(layer "F.SilkS")
			(effects
				(font
					(size 0.7 0.7)
					(thickness 0.15)
				)
				(justify right bottom)
			)
		)
		(property "Value" "TPS56C230"
			(at 0 2.898 0)
			(layer "F.Fab")
			(effects
				(font
					(size 0.7 0.7)
					(thickness 0.15)
				)
				(justify right bottom)
			)
		)
		(property "Datasheet" "https://www.ti.com/lit/ds/symlink/tps56c230.pdf?ts=1672843259715&ref_url=https%253A%252F%252Fwww.ti.com%252Fproduct%252FTPS56C230"
			(at 0 0 180)
			(layer "F.Fab")
			(hide yes)
			(effects
				(font
					(size 1.27 1.27)
					(thickness 0.15)
				)
			)
		)
		(property "Author" "Antmicro"
			(at 623.429998 241.117998 0)
			(layer "F.Fab")
			(hide yes)
			(effects
				(font
					(size 1 1)
					(thickness 0.15)
				)
			)
		)
		(property "License" "Apache-2.0"
			(at 623.429998 241.117998 0)
			(layer "F.Fab")
			(hide yes)
			(effects
				(font
					(size 1 1)
					(thickness 0.15)
				)
			)
		)
		(property "MPN" "TPS56C230RJER"
			(at 623.429998 241.117998 0)
			(layer "F.Fab")
			(hide yes)
			(effects
				(font
					(size 1 1)
					(thickness 0.15)
				)
			)
		)
		(property "Manufacturer" "Texas Instruments"
			(at 623.429998 241.117998 0)
			(layer "F.Fab")
			(hide yes)
			(effects
				(font
					(size 1 1)
					(thickness 0.15)
				)
			)
		)
		(sheetname "Power")
		(sheetfile "power.kicad_sch")
		(attr smd)
		(fp_line
			(start 1.5 -1.5)
			(end 1.5 -1.2)
			(stroke
				(width 0.15)
				(type solid)
			)
			(layer "F.SilkS")
		)
		(fp_line
			(start 1.499 1.5)
			(end 1.499 1.202)
			(stroke
				(width 0.15)
				(type solid)
			)
			(layer "F.SilkS")
		)
		(fp_line
			(start 1.202 -1.5)
			(end 1.5 -1.5)
			(stroke
				(width 0.15)
				(type solid)
			)
			(layer "F.SilkS")
		)
		(fp_line
			(start 1.201 1.5)
			(end 1.499 1.5)
			(stroke
				(width 0.15)
				(type solid)
			)
			(layer "F.SilkS")
		)
		(fp_line
			(start -1.2 1.498)
			(end -1.5 1.498)
			(stroke
				(width 0.15)
				(type solid)
			)
			(layer "F.SilkS")
		)
		(fp_line
			(start -1.5 1.498)
			(end -1.5 1.2)
			(stroke
				(width 0.15)
				(type solid)
			)
			(layer "F.SilkS")
		)
		(fp_line
			(start -1.5 -1.201)
			(end -1.5 -1.499)
			(stroke
				(width 0.15)
				(type solid)
			)
			(layer "F.SilkS")
		)
		(fp_line
			(start -1.5 -1.499)
			(end -1.2 -1.499)
			(stroke
				(width 0.15)
				(type solid)
			)
			(layer "F.SilkS")
		)
		(fp_circle
			(center -1.8 -1.15)
			(end -1.75 -1.15)
			(stroke
				(width 0.15)
				(type solid)
			)
			(fill yes)
			(layer "F.SilkS")
		)
		(fp_rect
			(start -1.8 -1.8)
			(end 1.8 1.8)
			(stroke
				(width 0.05)
				(type solid)
			)
			(fill no)
			(layer "F.CrtYd")
		)
		(fp_line
			(start 1.499 1.499)
			(end 1.499 -1.5)
			(stroke
				(width 0.15)
				(type solid)
			)
			(layer "F.Fab")
		)
		(fp_line
			(start 1.499 -1.5)
			(end -0.5 -1.5)
			(stroke
				(width 0.15)
				(type solid)
			)
			(layer "F.Fab")
		)
		(fp_line
			(start -0.5 -1.5)
			(end -1.5 -0.5)
			(stroke
				(width 0.15)
				(type solid)
			)
			(layer "F.Fab")
		)
		(fp_line
			(start -1.5 1.499)
			(end 1.499 1.499)
			(stroke
				(width 0.15)
				(type solid)
			)
			(layer "F.Fab")
		)
		(fp_line
			(start -1.5 -0.5)
			(end -1.5 1.499)
			(stroke
				(width 0.15)
				(type solid)
			)
			(layer "F.Fab")
		)
		(pad "1" smd oval
			(at -1.4 -0.905 270)
			(size 0.2 0.6)
			(layers "F.Cu" "F.Mask" "F.Paste")
			(net 66 "Net-(U18-BST)")
			(pinfunction "BST")
			(pintype "passive")
			(teardrops
				(best_length_ratio 0.2)
				(max_length 1)
				(best_width_ratio 0.9)
				(max_width 2)
				(curved_edges yes)
				(filter_ratio 0.9)
				(enabled yes)
				(allow_two_segments yes)
				(prefer_zone_connections yes)
			)
		)
		(pad "2" smd oval
			(at -1.4 -0.455 270)
			(size 0.2 0.6)
			(layers "F.Cu" "F.Mask" "F.Paste")
			(net 62 "+12V_AON")
			(pinfunction "V_{IN}")
			(pintype "power_in")
			(teardrops
				(best_length_ratio 0.2)
				(max_length 1)
				(best_width_ratio 0.9)
				(max_width 2)
				(curved_edges yes)
				(filter_ratio 0.9)
				(enabled yes)
				(allow_two_segments yes)
				(prefer_zone_connections yes)
			)
		)
		(pad "3" smd oval
			(at -1.4 0 270)
			(size 0.2 0.6)
			(layers "F.Cu" "F.Mask" "F.Paste")
			(net 62 "+12V_AON")
			(pinfunction "V_{IN}")
			(pintype "passive")
			(teardrops
				(best_length_ratio 0.2)
				(max_length 1)
				(best_width_ratio 0.9)
				(max_width 2)
				(curved_edges yes)
				(filter_ratio 0.9)
				(enabled yes)
				(allow_two_segments yes)
				(prefer_zone_connections yes)
			)
		)
		(pad "4" smd oval
			(at -1.4 0.45 270)
			(size 0.2 0.6)
			(layers "F.Cu" "F.Mask" "F.Paste")
			(net 62 "+12V_AON")
			(pinfunction "V_{IN}")
			(pintype "passive")
			(teardrops
				(best_length_ratio 0.2)
				(max_length 1)
				(best_width_ratio 0.9)
				(max_width 2)
				(curved_edges yes)
				(filter_ratio 0.9)
				(enabled yes)
				(allow_two_segments yes)
				(prefer_zone_connections yes)
			)
		)
		(pad "5" smd oval
			(at -1.4 0.9 270)
			(size 0.2 0.6)
			(layers "F.Cu" "F.Mask" "F.Paste")
			(net 62 "+12V_AON")
			(pinfunction "V_{IN}")
			(pintype "passive")
			(teardrops
				(best_length_ratio 0.2)
				(max_length 1)
				(best_width_ratio 0.9)
				(max_width 2)
				(curved_edges yes)
				(filter_ratio 0.9)
				(enabled yes)
				(allow_two_segments yes)
				(prefer_zone_connections yes)
			)
		)
		(pad "6" smd oval
			(at -0.905 1.4 180)
			(size 0.2 0.6)
			(layers "F.Cu" "F.Mask" "F.Paste")
			(net 67 "Net-(C47-Pad2)")
			(pinfunction "SW")
			(pintype "passive")
			(teardrops
				(best_length_ratio 0.2)
				(max_length 1)
				(best_width_ratio 0.9)
				(max_width 2)
				(curved_edges yes)
				(filter_ratio 0.9)
				(enabled yes)
				(allow_two_segments yes)
				(prefer_zone_connections yes)
			)
		)
		(pad "7" smd oval
			(at -0.455 1.4 180)
			(size 0.2 0.6)
			(layers "F.Cu" "F.Mask" "F.Paste")
			(net 1 "GND")
			(pinfunction "PGND")
			(pintype "passive")
			(teardrops
				(best_length_ratio 0.2)
				(max_length 1)
				(best_width_ratio 0.9)
				(max_width 2)
				(curved_edges yes)
				(filter_ratio 0.9)
				(enabled yes)
				(allow_two_segments yes)
				(prefer_zone_connections yes)
			)
		)
		(pad "8" smd oval
			(at 0 1.4 180)
			(size 0.2 0.6)
			(layers "F.Cu" "F.Mask" "F.Paste")
			(net 1 "GND")
			(pinfunction "PGND")
			(pintype "passive")
			(teardrops
				(best_length_ratio 0.2)
				(max_length 1)
				(best_width_ratio 0.9)
				(max_width 2)
				(curved_edges yes)
				(filter_ratio 0.9)
				(enabled yes)
				(allow_two_segments yes)
				(prefer_zone_connections yes)
			)
		)
		(pad "9" smd oval
			(at 0.45 1.4 180)
			(size 0.2 0.6)
			(layers "F.Cu" "F.Mask" "F.Paste")
			(net 578 "/Power/PG_{1V0}")
			(pinfunction "PG")
			(pintype "passive")
			(teardrops
				(best_length_ratio 0.2)
				(max_length 1)
				(best_width_ratio 0.9)
				(max_width 2)
				(curved_edges yes)
				(filter_ratio 0.9)
				(enabled yes)
				(allow_two_segments yes)
				(prefer_zone_connections yes)
			)
		)
		(pad "10" smd oval
			(at 0.9 1.4 180)
			(size 0.2 0.6)
			(layers "F.Cu" "F.Mask" "F.Paste")
			(net 773 "unconnected-(U18-NC-Pad10)")
			(pinfunction "NC")
			(pintype "no_connect")
			(teardrops
				(best_length_ratio 0.2)
				(max_length 1)
				(best_width_ratio 0.9)
				(max_width 2)
				(curved_edges yes)
				(filter_ratio 0.9)
				(enabled yes)
				(allow_two_segments yes)
				(prefer_zone_connections yes)
			)
		)
		(pad "11" smd oval
			(at 1.4 0.9 270)
			(size 0.2 0.6)
			(layers "F.Cu" "F.Mask" "F.Paste")
			(net 774 "unconnected-(U18-SS-Pad11)")
			(pinfunction "SS")
			(pintype "passive+no_connect")
			(teardrops
				(best_length_ratio 0.2)
				(max_length 1)
				(best_width_ratio 0.9)
				(max_width 2)
				(curved_edges yes)
				(filter_ratio 0.9)
				(enabled yes)
				(allow_two_segments yes)
				(prefer_zone_connections yes)
			)
		)
		(pad "12" smd oval
			(at 1.4 0.45 270)
			(size 0.2 0.6)
			(layers "F.Cu" "F.Mask" "F.Paste")
			(net 577 "Net-(U18-EN)")
			(pinfunction "EN")
			(pintype "passive")
			(teardrops
				(best_length_ratio 0.2)
				(max_length 1)
				(best_width_ratio 0.9)
				(max_width 2)
				(curved_edges yes)
				(filter_ratio 0.9)
				(enabled yes)
				(allow_two_segments yes)
				(prefer_zone_connections yes)
			)
		)
		(pad "13" smd oval
			(at 1.4 0 270)
			(size 0.2 0.6)
			(layers "F.Cu" "F.Mask" "F.Paste")
			(net 1 "GND")
			(pinfunction "AGND")
			(pintype "passive")
			(teardrops
				(best_length_ratio 0.2)
				(max_length 1)
				(best_width_ratio 0.9)
				(max_width 2)
				(curved_edges yes)
				(filter_ratio 0.9)
				(enabled yes)
				(allow_two_segments yes)
				(prefer_zone_connections yes)
			)
		)
		(pad "14" smd oval
			(at 1.4 -0.455 270)
			(size 0.2 0.6)
			(layers "F.Cu" "F.Mask" "F.Paste")
			(net 580 "Net-(U18-FB)")
			(pinfunction "FB")
			(pintype "passive")
			(teardrops
				(best_length_ratio 0.2)
				(max_length 1)
				(best_width_ratio 0.9)
				(max_width 2)
				(curved_edges yes)
				(filter_ratio 0.9)
				(enabled yes)
				(allow_two_segments yes)
				(prefer_zone_connections yes)
			)
		)
		(pad "15" smd oval
			(at 1.4 -0.905 270)
			(size 0.2 0.6)
			(layers "F.Cu" "F.Mask" "F.Paste")
			(net 575 "Net-(U18-MODE)")
			(pinfunction "MODE")
			(pintype "passive")
			(teardrops
				(best_length_ratio 0.2)
				(max_length 1)
				(best_width_ratio 0.9)
				(max_width 2)
				(curved_edges yes)
				(filter_ratio 0.9)
				(enabled yes)
				(allow_two_segments yes)
				(prefer_zone_connections yes)
			)
		)
		(pad "16" smd oval
			(at 0.9 -1.4 180)
			(size 0.2 0.6)
			(layers "F.Cu" "F.Mask" "F.Paste")
			(net 775 "unconnected-(U18-NC-Pad16)")
			(pinfunction "NC")
			(pintype "no_connect")
			(teardrops
				(best_length_ratio 0.2)
				(max_length 1)
				(best_width_ratio 0.9)
				(max_width 2)
				(curved_edges yes)
				(filter_ratio 0.9)
				(enabled yes)
				(allow_two_segments yes)
				(prefer_zone_connections yes)
			)
		)
		(pad "17" smd oval
			(at 0.45 -1.4 180)
			(size 0.2 0.6)
			(layers "F.Cu" "F.Mask" "F.Paste")
			(net 63 "Net-(U18-V_{CC})")
			(pinfunction "V_{CC}")
			(pintype "passive")
			(teardrops
				(best_length_ratio 0.2)
				(max_length 1)
				(best_width_ratio 0.9)
				(max_width 2)
				(curved_edges yes)
				(filter_ratio 0.9)
				(enabled yes)
				(allow_two_segments yes)
				(prefer_zone_connections yes)
			)
		)
		(pad "18" smd oval
			(at 0 -1.4 180)
			(size 0.2 0.6)
			(layers "F.Cu" "F.Mask" "F.Paste")
			(net 1 "GND")
			(pinfunction "PGND")
			(pintype "passive")
			(teardrops
				(best_length_ratio 0.2)
				(max_length 1)
				(best_width_ratio 0.9)
				(max_width 2)
				(curved_edges yes)
				(filter_ratio 0.9)
				(enabled yes)
				(allow_two_segments yes)
				(prefer_zone_connections yes)
			)
		)
		(pad "19" smd oval
			(at -0.455 -1.4 180)
			(size 0.2 0.6)
			(layers "F.Cu" "F.Mask" "F.Paste")
			(net 67 "Net-(C47-Pad2)")
			(pinfunction "SW")
			(pintype "passive")
			(teardrops
				(best_length_ratio 0.2)
				(max_length 1)
				(best_width_ratio 0.9)
				(max_width 2)
				(curved_edges yes)
				(filter_ratio 0.9)
				(enabled yes)
				(allow_two_segments yes)
				(prefer_zone_connections yes)
			)
		)
		(pad "20" smd oval
			(at -0.905 -1.4 180)
			(size 0.2 0.6)
			(layers "F.Cu" "F.Mask" "F.Paste")
			(net 67 "Net-(C47-Pad2)")
			(pinfunction "SW")
			(pintype "passive")
			(teardrops
				(best_length_ratio 0.2)
				(max_length 1)
				(best_width_ratio 0.9)
				(max_width 2)
				(curved_edges yes)
				(filter_ratio 0.9)
				(enabled yes)
				(allow_two_segments yes)
				(prefer_zone_connections yes)
			)
		)
		(pad "21" smd roundrect
			(at -0.06 0.018 180)
			(size 0.775 0.86)
			(layers "F.Cu" "F.Mask" "F.Paste")
			(roundrect_rratio 0.1)
			(net 1 "GND")
			(pinfunction "PGND")
			(pintype "passive")
			(solder_mask_margin -0.05)
			(solder_paste_margin -0.05)
			(teardrops
				(best_length_ratio 0.2)
				(max_length 1)
				(best_width_ratio 0.9)
				(max_width 2)
				(curved_edges yes)
				(filter_ratio 0.9)
				(enabled yes)
				(allow_two_segments yes)
				(prefer_zone_connections yes)
			)
		)
	)
	(footprint "antmicro-footprints:R_0201"
		(layer "F.Cu")
		(at 149.57 147.961 -90)
		(descr "Resistor SMD 0201")
		(tags "resistor SMD 0201")
		(property "Reference" "R277"
			(at 3.619 -0.28 90)
			(layer "F.SilkS")
			(effects
				(font
					(size 0.7 0.7)
					(thickness 0.15)
				)
				(justify right bottom)
			)
		)
		(property "Value" "R_0R_0201"
			(at 0 1.25 90)
			(layer "F.Fab")
			(effects
				(font
					(size 0.7 0.7)
					(thickness 0.15)
				)
				(justify right bottom)
			)
		)
		(property "Datasheet" "https://www.bourns.com/docs/product-datasheets/cr.pdf"
			(at 0 0 270)
			(layer "F.Fab")
			(hide yes)
			(effects
				(font
					(size 1.27 1.27)
					(thickness 0.15)
				)
			)
		)
		(property "Author" "Antmicro"
			(at 1.609 297.531 0)
			(layer "F.Fab")
			(hide yes)
			(effects
				(font
					(size 1 1)
					(thickness 0.15)
				)
			)
		)
		(property "License" "Apache-2.0"
			(at 1.609 297.531 0)
			(layer "F.Fab")
			(hide yes)
			(effects
				(font
					(size 1 1)
					(thickness 0.15)
				)
			)
		)
		(property "MPN" "CR0201-FX-0R00GLF"
			(at 1.609 297.531 0)
			(layer "F.Fab")
			(hide yes)
			(effects
				(font
					(size 1 1)
					(thickness 0.15)
				)
			)
		)
		(property "Manufacturer" "Bourns"
			(at 1.609 297.531 0)
			(layer "F.Fab")
			(hide yes)
			(effects
				(font
					(size 1 1)
					(thickness 0.15)
				)
			)
		)
		(property "Tolerance" "1%"
			(at 1.609 297.531 0)
			(layer "F.Fab")
			(hide yes)
			(effects
				(font
					(size 1 1)
					(thickness 0.15)
				)
			)
		)
		(property "Val" "0R"
			(at 1.609 297.531 0)
			(layer "F.Fab")
			(hide yes)
			(effects
				(font
					(size 1 1)
					(thickness 0.15)
				)
			)
		)
		(sheetname "KR to SFI #1")
		(sheetfile "kr_sfi.kicad_sch")
		(attr smd dnp)
		(fp_rect
			(start -0.7 -0.35)
			(end 0.7 0.35)
			(stroke
				(width 0.05)
				(type default)
			)
			(fill no)
			(layer "F.CrtYd")
		)
		(fp_rect
			(start -0.3 -0.15)
			(end 0.298 0.148)
			(stroke
				(width 0.15)
				(type solid)
			)
			(fill no)
			(layer "F.Fab")
		)
		(pad "" smd roundrect
			(at -0.346 0 270)
			(size 0.318 0.36)
			(layers "F.Paste")
			(roundrect_rratio 0.25)
			(teardrops
				(best_length_ratio 0.2)
				(max_length 1)
				(best_width_ratio 0.9)
				(max_width 2)
				(curved_edges yes)
				(filter_ratio 0.9)
				(enabled yes)
				(allow_two_segments yes)
				(prefer_zone_connections yes)
			)
		)
		(pad "" smd roundrect
			(at 0.344 0 270)
			(size 0.318 0.36)
			(layers "F.Paste")
			(roundrect_rratio 0.25)
			(teardrops
				(best_length_ratio 0.2)
				(max_length 1)
				(best_width_ratio 0.9)
				(max_width 2)
				(curved_edges yes)
				(filter_ratio 0.9)
				(enabled yes)
				(allow_two_segments yes)
				(prefer_zone_connections yes)
			)
		)
		(pad "1" smd roundrect
			(at -0.32 0 270)
			(size 0.46 0.4)
			(layers "F.Cu" "F.Mask")
			(roundrect_rratio 0.25)
			(net 171 "/2xSFP+/SFI0.RX+")
			(pintype "passive")
			(teardrops
				(best_length_ratio 0.2)
				(max_length 1)
				(best_width_ratio 0.9)
				(max_width 2)
				(curved_edges yes)
				(filter_ratio 0.9)
				(enabled yes)
				(allow_two_segments yes)
				(prefer_zone_connections yes)
			)
		)
		(pad "2" smd roundrect
			(at 0.32 0 270)
			(size 0.46 0.4)
			(layers "F.Cu" "F.Mask")
			(roundrect_rratio 0.25)
			(net 946 "/2xSFP+/KR to SFI #1/BYP_RX+")
			(pintype "passive")
			(teardrops
				(best_length_ratio 0.2)
				(max_length 1)
				(best_width_ratio 0.9)
				(max_width 2)
				(curved_edges yes)
				(filter_ratio 0.9)
				(enabled yes)
				(allow_two_segments yes)
				(prefer_zone_connections yes)
			)
		)
	)
	(footprint "antmicro-footprints:R_0402_1005Metric"
		(layer "F.Cu")
		(at 195.70861 77.152163 90)
		(descr "Resistor SMD 0402")
		(tags "resistor SMD 0402")
		(property "Reference" "R327"
			(at -1.9 -0.5 90)
			(layer "F.SilkS")
			(effects
				(font
					(size 0.7 0.7)
					(thickness 0.15)
				)
				(justify left bottom)
			)
		)
		(property "Value" "R_470R_0402"
			(at -1.011843 1.772047 90)
			(layer "F.Fab")
			(effects
				(font
					(size 0.7 0.7)
					(thickness 0.15)
				)
				(justify left bottom)
			)
		)
		(property "Datasheet" "https://www.bourns.com/docs/product-datasheets/cr.pdf"
			(at 0 0 90)
			(layer "F.Fab")
			(hide yes)
			(effects
				(font
					(size 1.27 1.27)
					(thickness 0.15)
				)
			)
		)
		(property "Author" "Antmicro"
			(at 272.860773 -118.556447 0)
			(layer "F.Fab")
			(hide yes)
			(effects
				(font
					(size 1 1)
					(thickness 0.15)
				)
			)
		)
		(property "License" "Apache-2.0"
			(at 272.860773 -118.556447 0)
			(layer "F.Fab")
			(hide yes)
			(effects
				(font
					(size 1 1)
					(thickness 0.15)
				)
			)
		)
		(property "MPN" "CR0402-FX-4700GLF"
			(at 272.860773 -118.556447 0)
			(layer "F.Fab")
			(hide yes)
			(effects
				(font
					(size 1 1)
					(thickness 0.15)
				)
			)
		)
		(property "Manufacturer" "Bourns"
			(at 272.860773 -118.556447 0)
			(layer "F.Fab")
			(hide yes)
			(effects
				(font
					(size 1 1)
					(thickness 0.15)
				)
			)
		)
		(property "Tolerance" "1%"
			(at 272.860773 -118.556447 0)
			(layer "F.Fab")
			(hide yes)
			(effects
				(font
					(size 1 1)
					(thickness 0.15)
				)
			)
		)
		(property "Val" "470R"
			(at 272.860773 -118.556447 0)
			(layer "F.Fab")
			(hide yes)
			(effects
				(font
					(size 1 1)
					(thickness 0.15)
				)
			)
		)
		(sheetname "Power")
		(sheetfile "power.kicad_sch")
		(attr smd)
		(fp_rect
			(start -0.925 -0.47)
			(end 0.925 0.47)
			(stroke
				(width 0.05)
				(type default)
			)
			(fill no)
			(layer "F.CrtYd")
		)
		(fp_rect
			(start -0.5 -0.25)
			(end 0.5 0.25)
			(stroke
				(width 0.15)
				(type solid)
			)
			(fill no)
			(layer "F.Fab")
		)
		(pad "1" smd roundrect
			(at -0.48 0 90)
			(size 0.59 0.64)
			(layers "F.Cu" "F.Mask" "F.Paste")
			(roundrect_rratio 0.25)
			(net 1 "GND")
			(pintype "passive")
			(teardrops
				(best_length_ratio 0.2)
				(max_length 1)
				(best_width_ratio 0.9)
				(max_width 2)
				(curved_edges yes)
				(filter_ratio 0.9)
				(enabled yes)
				(allow_two_segments yes)
				(prefer_zone_connections yes)
			)
		)
		(pad "2" smd roundrect
			(at 0.48 0 90)
			(size 0.59 0.64)
			(layers "F.Cu" "F.Mask" "F.Paste")
			(roundrect_rratio 0.25)
			(net 986 "Net-(D34-C)")
			(pintype "passive")
			(teardrops
				(best_length_ratio 0.2)
				(max_length 1)
				(best_width_ratio 0.9)
				(max_width 2)
				(curved_edges yes)
				(filter_ratio 0.9)
				(enabled yes)
				(allow_two_segments yes)
				(prefer_zone_connections yes)
			)
		)
	)
)
